FILE_TYPE = CONNECTIVITY;
{Allegro Design Entry HDL 17.2-2016 S081 (4005846) 1/11/2022}
"PAGE_NUMBER" = 150;
0"NC";
1"GND\g";
2"GND\g";
3"GND\g";
4"GND\g";
5"GND\g";
6"GND\g";
7"GND\g";
8"PVDD18_S5_P0\g";
9"U152_OE_N";
10"JTAG_TDI";
11"JTAG_TDO";
12"CPU1_JTAG_BUF_OE";
13"GND\g";
14"PVDD18_S5_P0\g";
15"PVDD18_S5_P0\g";
16"GND\g";
17"JTAG_TCK";
18"JTAG_TMS";
19"JTAG_TRST_N";
20"JTAG_DBREQ_N";
21"CPU0_JTAG_BUF_OE";
22"PVDD18_S5_P0\g";
23"PVDD18_S5_P0\g";
24"GND\g";
25"PVDD18_S5_P0\g";
26"JTAG_P1_R_TMS";
27"JTAG_P1_R_TRST_N";
28"JTAG_P1_R_DBREQ_N";
29"JTAG_P0_R_TMS";
30"JTAG_P0_R_TCK";
31"JTAG_P0_R_TRST_N";
32"JTAG_P0_R_DBREQ_N";
33"JTAG_P1_R_TCK";
34"JTAG_CPUX_TDI";
35"JTAG_CPUX_TDO";
36"JTAG_CPU1_TRST_N";
37"JTAG_CPU1_TMS";
38"JTAG_CPU1_TCK";
39"JTAG_CPU1_DBREQ_N";
40"JTAG_CPU0_TCK";
41"JTAG_CPU0_DBREQ_N";
42"JTAG_CPU0_TRST_N";
43"JTAG_CPU0_TMS";
%"GND"
"1","(-4650,5875)","0","pure_quanta_power","I13";
;
CDS_LIB"pure_quanta_power"
SIZE"1B"
HDL_POWER"GND";
"A<SIZE-1..0>\NAC"1;
%"Q_CAP"
"1","(-4650,6100)","0","pure_quanta","I14";
;
LOCATION"C1516"
$SEC"1"
CDS_SEC"1"
MATERIAL"X7R"
TOLERANCE"10%"
VALUE"0.1UF"
PART_NUMBER"CH4103K1B08"
VOLTAGE"16V"
PACK_TYPE"C0402"
CDS_LIB"pure_quanta";
"B"
$PN"2"1;
"A"
$PN"1"25;
%"UNIVERSAL_POWER"
"1","(-4800,6425)","0","pure_quanta_power","I15";
;
HDL_POWER"PVDD18_S5_P0"
CDS_LIB"pure_quanta_power";
"A"25;
%"GND"
"1","(-4800,4975)","0","pure_quanta_power","I16";
;
SIZE"1B"
CDS_LIB"pure_quanta_power"
HDL_POWER"GND";
"A<SIZE-1..0>\NAC"24;
%"GND"
"1","(-6050,5925)","0","pure_quanta_power","I17";
;
SIZE"1B"
CDS_LIB"pure_quanta_power"
HDL_POWER"GND";
"A<SIZE-1..0>\NAC"2;
%"UNIVERSAL_POWER"
"1","(-5850,6425)","0","pure_quanta_power","I18";
;
HDL_POWER"PVDD18_S5_P0"
CDS_LIB"pure_quanta_power";
"A"22;
%"Q_CAP"
"1","(-6050,6100)","0","pure_quanta","I19";
;
LOCATION"C1514"
$SEC"1"
CDS_SEC"1"
MATERIAL"X7R"
TOLERANCE"10%"
VALUE"0.1UF"
PART_NUMBER"CH4103K1B08"
VOLTAGE"16V"
PACK_TYPE"C0402"
CDS_LIB"pure_quanta";
"B"
$PN"2"2;
"A"
$PN"1"22;
%"Q_RES"
"1","(-3625,5550)","0","pure_quanta","I24";
;
LOCATION"R1641"
$SEC"1"
CDS_SEC"1"
MATERIAL"CHIP"
TOLERANCE"1%"
VALUE"22"
CDS_LIB"pure_quanta"
WATTAGE"1/16W"
PART_NUMBER"CS02202FB12"
PACK_TYPE"0402LF";
"B"
$PN"2"41;
"A"
$PN"1"32;
%"Q_RES"
"1","(-3625,5650)","0","pure_quanta","I25";
;
LOCATION"R1639"
$SEC"1"
CDS_SEC"1"
MATERIAL"CHIP"
TOLERANCE"1%"
VALUE"22"
CDS_LIB"pure_quanta"
WATTAGE"1/16W"
PART_NUMBER"CS02202FB12"
PACK_TYPE"0402LF";
"B"
$PN"2"43;
"A"
$PN"1"29;
%"Q_RES"
"1","(-3625,5600)","0","pure_quanta","I26";
;
LOCATION"R1640"
$SEC"1"
CDS_SEC"1"
MATERIAL"CHIP"
TOLERANCE"1%"
VALUE"22"
CDS_LIB"pure_quanta"
WATTAGE"1/16W"
PART_NUMBER"CS02202FB12"
PACK_TYPE"0402LF";
"B"
$PN"2"42;
"A"
$PN"1"31;
%"Q_RES"
"1","(-3625,5700)","0","pure_quanta","I27";
;
LOCATION"R1638"
$SEC"1"
CDS_SEC"1"
MATERIAL"CHIP"
TOLERANCE"1%"
VALUE"22"
CDS_LIB"pure_quanta"
WATTAGE"1/16W"
PART_NUMBER"CS02202FB12"
PACK_TYPE"0402LF";
"B"
$PN"2"40;
"A"
$PN"1"30;
%"SN74AVC4T774PWR"
"1","(-5325,3875)","0","pure_quanta","I28";
;
LOCATION"U151"
$SEC"1"
CDS_SEC"1"
PART_TYPE"SMLF"
MATERIAL"IC"
VALUE"SN74AVC4T774PWR"
PART_NUMBER"AL04T774K00"
NEEDS_NO_SIZE"TRUE"
CDS_LMAN_SYM_OUTLINE"-250,450,250,-450"
CDS_LIB"pure_quanta";
"VCCA"
$PN"16"14;
"VCCB"
$PN"15"23;
"B1"
$PN"14"33;
"B2"
$PN"13"26;
"B3"
$PN"12"27;
"B4"
$PN"11"28;
"GND"
$PN"10"16;
"OE \B"
$PN"9"12;
"DIR4"
$PN"8"14;
"DIR3"
$PN"7"14;
"A4"
$PN"6"20;
"A3"
$PN"5"19;
"A2"
$PN"4"18;
"A1"
$PN"3"17;
"DIR2"
$PN"2"14;
"DIR1"
$PN"1"14;
%"Q_RES"
"1","(-3625,4025)","0","pure_quanta","I33";
;
LOCATION"R1642"
$SEC"1"
CDS_SEC"1"
MATERIAL"CHIP"
TOLERANCE"1%"
VALUE"22"
CDS_LIB"pure_quanta"
WATTAGE"1/16W"
PART_NUMBER"CS02202FB12"
PACK_TYPE"0402LF";
"B"
$PN"2"38;
"A"
$PN"1"33;
%"Q_RES"
"1","(-3625,3975)","0","pure_quanta","I34";
;
LOCATION"R1643"
$SEC"1"
CDS_SEC"1"
MATERIAL"CHIP"
TOLERANCE"1%"
VALUE"22"
CDS_LIB"pure_quanta"
WATTAGE"1/16W"
PART_NUMBER"CS02202FB12"
PACK_TYPE"0402LF";
"B"
$PN"2"37;
"A"
$PN"1"26;
%"Q_RES"
"1","(-3625,3925)","0","pure_quanta","I35";
;
LOCATION"R1644"
$SEC"1"
CDS_SEC"1"
MATERIAL"CHIP"
TOLERANCE"1%"
VALUE"22"
CDS_LIB"pure_quanta"
WATTAGE"1/16W"
PART_NUMBER"CS02202FB12"
PACK_TYPE"0402LF";
"B"
$PN"2"36;
"A"
$PN"1"27;
%"Q_RES"
"1","(-3625,3875)","0","pure_quanta","I36";
;
LOCATION"R1645"
$SEC"1"
CDS_SEC"1"
MATERIAL"CHIP"
TOLERANCE"1%"
VALUE"22"
CDS_LIB"pure_quanta"
WATTAGE"1/16W"
PART_NUMBER"CS02202FB12"
PACK_TYPE"0402LF";
"B"
$PN"2"39;
"A"
$PN"1"28;
%"UNIVERSAL_POWER"
"1","(-4800,4725)","0","pure_quanta_power","I37";
;
HDL_POWER"PVDD18_S5_P0"
CDS_LIB"pure_quanta_power";
"A"23;
%"UNIVERSAL_POWER"
"1","(-5850,4725)","0","pure_quanta_power","I38";
;
HDL_POWER"PVDD18_S5_P0"
CDS_LIB"pure_quanta_power";
"A"14;
%"GND"
"1","(-4650,4175)","0","pure_quanta_power","I39";
;
CDS_LIB"pure_quanta_power"
SIZE"1B"
HDL_POWER"GND";
"A<SIZE-1..0>\NAC"3;
%"Q_CAP"
"1","(-4650,4400)","0","pure_quanta","I40";
;
LOCATION"C1517"
$SEC"1"
CDS_SEC"1"
MATERIAL"X7R"
TOLERANCE"10%"
VALUE"0.1UF"
PART_NUMBER"CH4103K1B08"
VOLTAGE"16V"
PACK_TYPE"C0402"
CDS_LIB"pure_quanta";
"B"
$PN"2"3;
"A"
$PN"1"23;
%"GND"
"1","(-4800,3350)","0","pure_quanta_power","I41";
;
SIZE"1B"
CDS_LIB"pure_quanta_power"
HDL_POWER"GND";
"A<SIZE-1..0>\NAC"16;
%"GND"
"1","(-6050,4225)","0","pure_quanta_power","I42";
;
CDS_LIB"pure_quanta_power"
SIZE"1B"
HDL_POWER"GND";
"A<SIZE-1..0>\NAC"4;
%"Q_CAP"
"1","(-6050,4450)","0","pure_quanta","I43";
;
LOCATION"C1515"
$SEC"1"
CDS_SEC"1"
MATERIAL"X7R"
TOLERANCE"10%"
VALUE"0.1UF"
PART_NUMBER"CH4103K1B08"
VOLTAGE"16V"
PACK_TYPE"C0402"
CDS_LIB"pure_quanta";
"B"
$PN"2"4;
"A"
$PN"1"14;
%"SN74AVC2T245RSWR"
"1","(-5325,2175)","2","pure_quanta","I60";
;
LOCATION"U152"
$SEC"1"
CDS_SEC"1"
PART_TYPE"SMLF"
MATERIAL"IC"
VALUE"SN74AVC2T245RSWR"
PART_NUMBER"AL02T245000"
CDS_LIB"pure_quanta"
CDS_LMAN_SYM_OUTLINE"-250,375,250,-375"
NEEDS_NO_SIZE"TRUE";
"DIR1"
$PN"10"8;
"A2"
$PN"9"11;
"A1"
$PN"8"10;
"VCCA"
$PN"7"15;
"VCCB"
$PN"6"15;
"B1"
$PN"5"34;
"B2"
$PN"4"35;
"GND"
$PN"3"13;
"OE_# \B"
$PN"2"9;
"DIR2"
$PN"1"13;
%"GND"
"1","(-6025,1750)","0","pure_quanta_power","I63";
;
SIZE"1B"
CDS_LIB"pure_quanta_power"
HDL_POWER"GND";
"A<SIZE-1..0>\NAC"13;
%"UNIVERSAL_POWER"
"1","(-4775,2975)","0","pure_quanta_power","I64";
;
HDL_POWER"PVDD18_S5_P0"
CDS_LIB"pure_quanta_power";
"A"15;
%"GND"
"1","(-4650,2475)","0","pure_quanta_power","I65";
;
CDS_LIB"pure_quanta_power"
SIZE"1B"
HDL_POWER"GND";
"A<SIZE-1..0>\NAC"5;
%"Q_CAP"
"1","(-4650,2700)","0","pure_quanta","I66";
;
LOCATION"C1518"
$SEC"1"
CDS_SEC"1"
MATERIAL"X7R"
TOLERANCE"10%"
VALUE"0.1UF"
PART_NUMBER"CH4103K1B08"
VOLTAGE"16V"
PACK_TYPE"C0402"
CDS_LIB"pure_quanta";
"B"
$PN"2"5;
"A"
$PN"1"15;
%"UNIVERSAL_POWER"
"1","(-6025,2975)","0","pure_quanta_power","I67";
;
HDL_POWER"PVDD18_S5_P0"
CDS_LIB"pure_quanta_power";
"A"8;
%"GND"
"1","(-6225,2475)","0","pure_quanta_power","I68";
;
CDS_LIB"pure_quanta_power"
SIZE"1B"
HDL_POWER"GND";
"A<SIZE-1..0>\NAC"6;
%"Q_CAP"
"1","(-6225,2700)","0","pure_quanta","I69";
;
LOCATION"C1513"
$SEC"1"
CDS_SEC"1"
MATERIAL"X7R"
TOLERANCE"10%"
VALUE"0.1UF"
PART_NUMBER"CH4103K1B08"
VOLTAGE"16V"
PACK_TYPE"C0402"
CDS_LIB"pure_quanta";
"B"
$PN"2"6;
"A"
$PN"1"8;
%"GND"
"1","(-6600,1525)","0","pure_quanta_power","I70";
;
SIZE"1B"
CDS_LIB"pure_quanta_power"
HDL_POWER"GND";
"A<SIZE-1..0>\NAC"7;
%"Q_RES"
"2","(-6600,1800)","2","pure_quanta","I71";
;
LOCATION"R1637"
$SEC"1"
CDS_SEC"1"
WATTAGE"1/16W"
MATERIAL"CHIP"
TOLERANCE"5%"
VALUE"4.7K"
PART_NUMBER"TMP_QCS24702JB38"
PACK_TYPE"0402LF"
CDS_LIB"pure_quanta";
"A"
$PN"1"9;
"B"
$PN"2"7;
%"SN74AVC4T774PWR"
"1","(-5325,5550)","0","pure_quanta","I8";
;
LOCATION"U150"
$SEC"1"
CDS_SEC"1"
PART_TYPE"SMLF"
MATERIAL"IC"
VALUE"SN74AVC4T774PWR"
PART_NUMBER"AL04T774K00"
NEEDS_NO_SIZE"TRUE"
CDS_LMAN_SYM_OUTLINE"-250,450,250,-450"
CDS_LIB"pure_quanta";
"VCCA"
$PN"16"22;
"VCCB"
$PN"15"25;
"B1"
$PN"14"30;
"B2"
$PN"13"29;
"B3"
$PN"12"31;
"B4"
$PN"11"32;
"GND"
$PN"10"24;
"OE \B"
$PN"9"21;
"DIR4"
$PN"8"22;
"DIR3"
$PN"7"22;
"A4"
$PN"6"20;
"A3"
$PN"5"19;
"A2"
$PN"4"18;
"A1"
$PN"3"17;
"DIR2"
$PN"2"22;
"DIR1"
$PN"1"22;
END.
